(kicad_pcb
	(version 20260206)
	(generator "pcbnew")
	(generator_version "10.0")
	(general
		(thickness 1.6)
		(legacy_teardrops no)
	)
	(paper "A4")
	(title_block
		(title "04192023_DAF0TMB3IC0_F0TG_MB_C_brd_V02_OCP.brd")
		(comment 1 "Grand Teton / footprint 655 of 8354 (U6013), pads 1-111 of 354")
	)
	(layers
		(0 "F.Cu" signal "TOP")
		(4 "In1.Cu" signal "GND")
		(6 "In2.Cu" signal "IN1")
		(8 "In3.Cu" signal "GND1")
		(10 "In4.Cu" signal "IN2")
		(12 "In5.Cu" signal "GND2")
		(14 "In6.Cu" signal "IN3")
		(16 "In7.Cu" signal "GND3")
		(18 "In8.Cu" signal "VCC")
		(20 "In9.Cu" signal "VCC1")
		(22 "In10.Cu" signal "GND4")
		(24 "In11.Cu" signal "IN4")
		(26 "In12.Cu" signal "GND5")
		(28 "In13.Cu" signal "IN5")
		(30 "In14.Cu" signal "GND6")
		(32 "In15.Cu" signal "IN6")
		(34 "In16.Cu" signal "GND7")
		(2 "B.Cu" signal "BOTTOM")
		(9 "F.Adhes" user "F.Adhesive")
		(11 "B.Adhes" user "B.Adhesive")
		(13 "F.Paste" user "Package Geometry/Pastemask Top")
		(15 "B.Paste" user "Package Geometry/Pastemask Bottom")
		(5 "F.SilkS" user "Ref Des/Silkscreen Top")
		(7 "B.SilkS" user "Ref Des/Silkscreen Bottom")
		(1 "F.Mask" user "Board Geometry/Soldermask Top")
		(3 "B.Mask" user "Board Geometry/Soldermask Bottom")
		(17 "Dwgs.User" user "User.Drawings")
		(19 "Cmts.User" user "User.Comments")
		(21 "Eco1.User" user "User.Eco1")
		(23 "Eco2.User" user "User.Eco2")
		(25 "Edge.Cuts" user "Board Geometry/Outline")
		(27 "Margin" user)
		(31 "F.CrtYd" user "Package Geometry/Place Bound Top")
		(29 "B.CrtYd" user "Package Geometry/Place Bound Bottom")
		(35 "F.Fab" user "Ref Des/Assembly Top")
		(33 "B.Fab" user "Ref Des/Assembly Bottom")
	)
	(footprint ""
		(layer "F.Cu")
		(at 379.567948 -395.724634)
		(property "Reference" "U6013"
			(at -8.471916 -7.649972 0)
			(unlocked yes)
			(layer "F.SilkS")
			(effects
				(font
					(size 0.7874 0.5842)
					(thickness 0.1524)
				)
				(justify left)
			)
		)
		(property "Value" ""
			(at 0 0 0)
			(layer "F.Fab")
			(effects
				(font
					(size 1.27 1.27)
				)
			)
		)
		(duplicate_pad_numbers_are_jumpers no)
		(pad "A1" smd oval
			(at 11.050016 -3.938524)
			(size 0.254 0.3302)
			(layers "F.Cu" "F.Mask" "F.Paste")
			(net "NCF_A1_CPU0_P3_GND")
		)
		(pad "A35" smd oval
			(at 11.050016 3.940048)
			(size 0.254 0.3302)
			(layers "F.Cu" "F.Mask" "F.Paste")
			(net "NCF_CPU0_P3_GND")
		)
		(pad "AA10" smd circle
			(at 7.602728 -1.431798)
			(size 0.381 0.381)
			(layers "F.Cu" "F.Mask" "F.Paste")
			(net "P5E_CPU0_P3_TX_BUF_DN<14>")
		)
		(pad "AA29" smd circle
			(at 7.602728 2.032254)
			(size 0.381 0.381)
			(layers "F.Cu" "F.Mask" "F.Paste")
			(net "P5E_CPU0_P3_RX_DN<14>")
		)
		(pad "AB1" smd oval
			(at 7.450074 -3.938524)
			(size 0.254 0.3302)
			(layers "F.Cu" "F.Mask" "F.Paste")
			(net "P5E_CPU0_P3_RX_BUF_DP<14>")
		)
		(pad "AB35" smd oval
			(at 7.450074 3.940048)
			(size 0.254 0.3302)
			(layers "F.Cu" "F.Mask" "F.Paste")
			(net "P5E_CPU0_P3_TX_C_DN<14>")
		)
		(pad "AC4" smd circle
			(at 7.202678 -2.817368)
			(size 0.381 0.381)
			(layers "F.Cu" "F.Mask" "F.Paste")
			(net "GND")
		)
		(pad "AC13" smd circle
			(at 7.202678 -0.79629)
			(size 0.3048 0.3048)
			(layers "F.Cu" "F.Mask" "F.Paste")
			(net "GND")
		)
		(pad "AC17" smd circle
			(at 7.202678 -0.296164)
			(size 0.3048 0.3048)
			(layers "F.Cu" "F.Mask" "F.Paste")
			(net "P0V9_CPU0_RT3_2A")
		)
		(pad "AC20" smd circle
			(at 7.202678 0.203708)
			(size 0.3048 0.3048)
			(layers "F.Cu" "F.Mask" "F.Paste")
			(net "P0V9_CPU0_RT3_2A")
		)
		(pad "AC22" smd circle
			(at 7.202678 0.703834)
			(size 0.3048 0.3048)
			(layers "F.Cu" "F.Mask" "F.Paste")
			(net "GND")
		)
		(pad "AC32" smd circle
			(at 7.202678 2.724912)
			(size 0.381 0.381)
			(layers "F.Cu" "F.Mask" "F.Paste")
			(net "GND")
		)
		(pad "AD2" smd circle
			(at 7.1501 -3.41884)
			(size 0.3048 0.3048)
			(layers "F.Cu" "F.Mask" "F.Paste")
			(net "GND")
		)
		(pad "AD34" smd circle
			(at 7.1501 3.420364)
			(size 0.3048 0.3048)
			(layers "F.Cu" "F.Mask" "F.Paste")
			(net "GND")
		)
		(pad "AE1" smd oval
			(at 6.849872 -3.938524)
			(size 0.254 0.3302)
			(layers "F.Cu" "F.Mask" "F.Paste")
			(net "GND")
		)
		(pad "AE35" smd oval
			(at 6.849872 3.940048)
			(size 0.254 0.3302)
			(layers "F.Cu" "F.Mask" "F.Paste")
			(net "GND")
		)
		(pad "AF7" smd circle
			(at 6.802628 -2.12471)
			(size 0.381 0.381)
			(layers "F.Cu" "F.Mask" "F.Paste")
			(net "P5E_CPU0_P3_TX_BUF_DP<13>")
		)
		(pad "AF26" smd circle
			(at 6.802628 1.339342)
			(size 0.381 0.381)
			(layers "F.Cu" "F.Mask" "F.Paste")
			(net "P5E_CPU0_P3_RX_DP<13>")
		)
		(pad "AG2" smd circle
			(at 6.549898 -3.41884)
			(size 0.3048 0.3048)
			(layers "F.Cu" "F.Mask" "F.Paste")
			(net "P5E_CPU0_P3_RX_BUF_DN<13>")
		)
		(pad "AG34" smd circle
			(at 6.549898 3.420364)
			(size 0.3048 0.3048)
			(layers "F.Cu" "F.Mask" "F.Paste")
			(net "P5E_CPU0_P3_TX_C_DN<13>")
		)
		(pad "AH10" smd circle
			(at 6.402578 -1.431798)
			(size 0.381 0.381)
			(layers "F.Cu" "F.Mask" "F.Paste")
			(net "P5E_CPU0_P3_TX_BUF_DN<13>")
		)
		(pad "AH29" smd circle
			(at 6.402578 2.032254)
			(size 0.381 0.381)
			(layers "F.Cu" "F.Mask" "F.Paste")
			(net "P5E_CPU0_P3_RX_DN<13>")
		)
		(pad "AJ1" smd oval
			(at 6.249924 -3.938524)
			(size 0.254 0.3302)
			(layers "F.Cu" "F.Mask" "F.Paste")
			(net "P5E_CPU0_P3_RX_BUF_DP<13>")
		)
		(pad "AJ35" smd oval
			(at 6.249924 3.940048)
			(size 0.254 0.3302)
			(layers "F.Cu" "F.Mask" "F.Paste")
			(net "P5E_CPU0_P3_TX_C_DP<13>")
		)
		(pad "AK4" smd circle
			(at 6.002528 -2.817368)
			(size 0.381 0.381)
			(layers "F.Cu" "F.Mask" "F.Paste")
			(net "GND")
		)
		(pad "AK13" smd circle
			(at 6.002528 -0.79629)
			(size 0.3048 0.3048)
			(layers "F.Cu" "F.Mask" "F.Paste")
			(net "GND")
		)
		(pad "AK17" smd circle
			(at 6.002528 -0.296164)
			(size 0.3048 0.3048)
			(layers "F.Cu" "F.Mask" "F.Paste")
			(net "P0V9_CPU0_RT3_2A")
		)
		(pad "AK20" smd circle
			(at 6.002528 0.203708)
			(size 0.3048 0.3048)
			(layers "F.Cu" "F.Mask" "F.Paste")
			(net "P0V9_CPU0_RT3_2A")
		)
		(pad "AK22" smd circle
			(at 6.002528 0.703834)
			(size 0.3048 0.3048)
			(layers "F.Cu" "F.Mask" "F.Paste")
			(net "GND")
		)
		(pad "AK32" smd circle
			(at 6.002528 2.724912)
			(size 0.381 0.381)
			(layers "F.Cu" "F.Mask" "F.Paste")
			(net "GND")
		)
		(pad "AL2" smd circle
			(at 5.94995 -3.41884)
			(size 0.3048 0.3048)
			(layers "F.Cu" "F.Mask" "F.Paste")
			(net "GND")
		)
		(pad "AL34" smd circle
			(at 5.94995 3.420364)
			(size 0.3048 0.3048)
			(layers "F.Cu" "F.Mask" "F.Paste")
			(net "GND")
		)
		(pad "AM1" smd oval
			(at 5.649976 -3.938524)
			(size 0.254 0.3302)
			(layers "F.Cu" "F.Mask" "F.Paste")
			(net "GND")
		)
		(pad "AM35" smd oval
			(at 5.649976 3.940048)
			(size 0.254 0.3302)
			(layers "F.Cu" "F.Mask" "F.Paste")
			(net "GND")
		)
		(pad "AN7" smd circle
			(at 5.602478 -2.12471)
			(size 0.381 0.381)
			(layers "F.Cu" "F.Mask" "F.Paste")
			(net "P5E_CPU0_P3_TX_BUF_DP<12>")
		)
		(pad "AN26" smd circle
			(at 5.602478 1.339342)
			(size 0.381 0.381)
			(layers "F.Cu" "F.Mask" "F.Paste")
			(net "P5E_CPU0_P3_RX_DP<12>")
		)
		(pad "AP2" smd circle
			(at 5.350002 -3.41884)
			(size 0.3048 0.3048)
			(layers "F.Cu" "F.Mask" "F.Paste")
			(net "P5E_CPU0_P3_RX_BUF_DN<12>")
		)
		(pad "AP34" smd circle
			(at 5.350002 3.420364)
			(size 0.3048 0.3048)
			(layers "F.Cu" "F.Mask" "F.Paste")
			(net "P5E_CPU0_P3_TX_C_DN<12>")
		)
		(pad "AR10" smd circle
			(at 5.202682 -1.431798)
			(size 0.381 0.381)
			(layers "F.Cu" "F.Mask" "F.Paste")
			(net "P5E_CPU0_P3_TX_BUF_DN<12>")
		)
		(pad "AR29" smd circle
			(at 5.202682 2.032254)
			(size 0.381 0.381)
			(layers "F.Cu" "F.Mask" "F.Paste")
			(net "P5E_CPU0_P3_RX_DN<12>")
		)
		(pad "AT1" smd oval
			(at 5.050028 -3.938524)
			(size 0.254 0.3302)
			(layers "F.Cu" "F.Mask" "F.Paste")
			(net "P5E_CPU0_P3_RX_BUF_DP<12>")
		)
		(pad "AT35" smd oval
			(at 5.050028 3.940048)
			(size 0.254 0.3302)
			(layers "F.Cu" "F.Mask" "F.Paste")
			(net "P5E_CPU0_P3_TX_C_DP<12>")
		)
		(pad "AU4" smd circle
			(at 4.802632 -2.817368)
			(size 0.381 0.381)
			(layers "F.Cu" "F.Mask" "F.Paste")
			(net "GND")
		)
		(pad "AU13" smd circle
			(at 4.802632 -0.79629)
			(size 0.3048 0.3048)
			(layers "F.Cu" "F.Mask" "F.Paste")
			(net "GND")
		)
		(pad "AU17" smd circle
			(at 4.802632 -0.296164)
			(size 0.3048 0.3048)
			(layers "F.Cu" "F.Mask" "F.Paste")
			(net "P0V9_CPU0_RT3_2A")
		)
		(pad "AU20" smd circle
			(at 4.802632 0.203708)
			(size 0.3048 0.3048)
			(layers "F.Cu" "F.Mask" "F.Paste")
			(net "P0V9_CPU0_RT3_2A")
		)
		(pad "AU22" smd circle
			(at 4.802632 0.703834)
			(size 0.3048 0.3048)
			(layers "F.Cu" "F.Mask" "F.Paste")
			(net "GND")
		)
		(pad "AU32" smd circle
			(at 4.802632 2.724912)
			(size 0.381 0.381)
			(layers "F.Cu" "F.Mask" "F.Paste")
			(net "GND")
		)
		(pad "AV2" smd circle
			(at 4.750054 -3.41884)
			(size 0.3048 0.3048)
			(layers "F.Cu" "F.Mask" "F.Paste")
			(net "GND")
		)
		(pad "AV34" smd circle
			(at 4.750054 3.420364)
			(size 0.3048 0.3048)
			(layers "F.Cu" "F.Mask" "F.Paste")
			(net "GND")
		)
		(pad "AW1" smd oval
			(at 4.45008 -3.938524)
			(size 0.254 0.3302)
			(layers "F.Cu" "F.Mask" "F.Paste")
			(net "GND")
		)
		(pad "AW35" smd oval
			(at 4.45008 3.940048)
			(size 0.254 0.3302)
			(layers "F.Cu" "F.Mask" "F.Paste")
			(net "GND")
		)
		(pad "AY7" smd circle
			(at 4.402582 -2.12471)
			(size 0.381 0.381)
			(layers "F.Cu" "F.Mask" "F.Paste")
			(net "P5E_CPU0_P3_TX_BUF_DP<11>")
		)
		(pad "AY26" smd circle
			(at 4.402582 1.339342)
			(size 0.381 0.381)
			(layers "F.Cu" "F.Mask" "F.Paste")
			(net "P5E_CPU0_P3_RX_DP<11>")
		)
		(pad "B3" smd oval
			(at 10.885932 -2.888488 90)
			(size 0.254 0.3302)
			(layers "F.Cu" "F.Mask" "F.Paste")
			(net "JTAG_TCK_RT_CPU0_P3")
		)
		(pad "B6" smd oval
			(at 10.885932 -2.288286 90)
			(size 0.254 0.3302)
			(layers "F.Cu" "F.Mask" "F.Paste")
			(net "JTAG_TDI_RT_CPU0_P3")
		)
		(pad "B9" smd oval
			(at 10.885932 -1.688338 90)
			(size 0.254 0.3302)
			(layers "F.Cu" "F.Mask" "F.Paste")
			(net "JTAG_TDO_RT_CPU0_P3")
		)
		(pad "B12" smd oval
			(at 10.885932 -1.08839 90)
			(size 0.254 0.3302)
			(layers "F.Cu" "F.Mask" "F.Paste")
			(net "JTAG_TMS_RT_CPU0_P3")
		)
		(pad "B16" smd oval
			(at 10.885932 -0.488442 90)
			(size 0.254 0.3302)
			(layers "F.Cu" "F.Mask" "F.Paste")
			(net "Net_2215")
		)
		(pad "B19" smd oval
			(at 10.885932 0.111506 90)
			(size 0.254 0.3302)
			(layers "F.Cu" "F.Mask" "F.Paste")
			(net "GND")
		)
		(pad "B23" smd oval
			(at 10.885932 0.711708 90)
			(size 0.254 0.3302)
			(layers "F.Cu" "F.Mask" "F.Paste")
			(net "RT_CPU0_P3_ADDR2")
		)
		(pad "B25" smd oval
			(at 10.885932 1.311656 90)
			(size 0.254 0.3302)
			(layers "F.Cu" "F.Mask" "F.Paste")
			(net "RT_CPU0_P3_ADDR3")
		)
		(pad "B28" smd oval
			(at 10.885932 1.911604 90)
			(size 0.254 0.3302)
			(layers "F.Cu" "F.Mask" "F.Paste")
			(net "SMB_RT_CPU0_P3_R2_SDA")
		)
		(pad "B31" smd oval
			(at 10.885932 2.511552 90)
			(size 0.254 0.3302)
			(layers "F.Cu" "F.Mask" "F.Paste")
			(net "SMB_RT_CPU0_P3_R2_SCL")
		)
		(pad "BA2" smd circle
			(at 4.150106 -3.41884)
			(size 0.3048 0.3048)
			(layers "F.Cu" "F.Mask" "F.Paste")
			(net "P5E_CPU0_P3_RX_BUF_DN<11>")
		)
		(pad "BA34" smd circle
			(at 4.150106 3.420364)
			(size 0.3048 0.3048)
			(layers "F.Cu" "F.Mask" "F.Paste")
			(net "P5E_CPU0_P3_TX_C_DN<11>")
		)
		(pad "BB10" smd circle
			(at 4.002532 -1.431798)
			(size 0.381 0.381)
			(layers "F.Cu" "F.Mask" "F.Paste")
			(net "P5E_CPU0_P3_TX_BUF_DN<11>")
		)
		(pad "BB29" smd circle
			(at 4.002532 2.032254)
			(size 0.381 0.381)
			(layers "F.Cu" "F.Mask" "F.Paste")
			(net "P5E_CPU0_P3_RX_DN<11>")
		)
		(pad "BC1" smd oval
			(at 3.849878 -3.938524)
			(size 0.254 0.3302)
			(layers "F.Cu" "F.Mask" "F.Paste")
			(net "P5E_CPU0_P3_RX_BUF_DP<11>")
		)
		(pad "BC35" smd oval
			(at 3.849878 3.940048)
			(size 0.254 0.3302)
			(layers "F.Cu" "F.Mask" "F.Paste")
			(net "P5E_CPU0_P3_TX_C_DP<11>")
		)
		(pad "BD4" smd circle
			(at 3.602482 -2.817368)
			(size 0.381 0.381)
			(layers "F.Cu" "F.Mask" "F.Paste")
			(net "GND")
		)
		(pad "BD13" smd circle
			(at 3.602482 -0.79629)
			(size 0.3048 0.3048)
			(layers "F.Cu" "F.Mask" "F.Paste")
			(net "GND")
		)
		(pad "BD17" smd circle
			(at 3.602482 -0.296164)
			(size 0.3048 0.3048)
			(layers "F.Cu" "F.Mask" "F.Paste")
			(net "P0V9_CPU0_RT3_2A_2D")
		)
		(pad "BD20" smd circle
			(at 3.602482 0.203708)
			(size 0.3048 0.3048)
			(layers "F.Cu" "F.Mask" "F.Paste")
			(net "P0V9_CPU0_RT3_2A_2D")
		)
		(pad "BD22" smd circle
			(at 3.602482 0.703834)
			(size 0.3048 0.3048)
			(layers "F.Cu" "F.Mask" "F.Paste")
			(net "GND")
		)
		(pad "BD32" smd circle
			(at 3.602482 2.724912)
			(size 0.381 0.381)
			(layers "F.Cu" "F.Mask" "F.Paste")
			(net "GND")
		)
		(pad "BE2" smd circle
			(at 3.549904 -3.41884)
			(size 0.3048 0.3048)
			(layers "F.Cu" "F.Mask" "F.Paste")
			(net "GND")
		)
		(pad "BE34" smd circle
			(at 3.549904 3.420364)
			(size 0.3048 0.3048)
			(layers "F.Cu" "F.Mask" "F.Paste")
			(net "GND")
		)
		(pad "BF1" smd oval
			(at 3.24993 -3.938524)
			(size 0.254 0.3302)
			(layers "F.Cu" "F.Mask" "F.Paste")
			(net "GND")
		)
		(pad "BF35" smd oval
			(at 3.24993 3.940048)
			(size 0.254 0.3302)
			(layers "F.Cu" "F.Mask" "F.Paste")
			(net "GND")
		)
		(pad "BG7" smd circle
			(at 3.202686 -2.12471)
			(size 0.381 0.381)
			(layers "F.Cu" "F.Mask" "F.Paste")
			(net "P5E_CPU0_P3_TX_BUF_DP<10>")
		)
		(pad "BG26" smd circle
			(at 3.202686 1.339342)
			(size 0.381 0.381)
			(layers "F.Cu" "F.Mask" "F.Paste")
			(net "P5E_CPU0_P3_RX_DP<10>")
		)
		(pad "BH2" smd circle
			(at 2.949956 -3.41884)
			(size 0.3048 0.3048)
			(layers "F.Cu" "F.Mask" "F.Paste")
			(net "P5E_CPU0_P3_RX_BUF_DN<10>")
		)
		(pad "BH34" smd circle
			(at 2.949956 3.420364)
			(size 0.3048 0.3048)
			(layers "F.Cu" "F.Mask" "F.Paste")
			(net "P5E_CPU0_P3_TX_C_DN<10>")
		)
		(pad "BJ10" smd circle
			(at 2.802636 -1.431798)
			(size 0.381 0.381)
			(layers "F.Cu" "F.Mask" "F.Paste")
			(net "P5E_CPU0_P3_TX_BUF_DN<10>")
		)
		(pad "BJ29" smd circle
			(at 2.802636 2.032254)
			(size 0.381 0.381)
			(layers "F.Cu" "F.Mask" "F.Paste")
			(net "P5E_CPU0_P3_RX_DN<10>")
		)
		(pad "BK1" smd oval
			(at 2.649982 -3.938524)
			(size 0.254 0.3302)
			(layers "F.Cu" "F.Mask" "F.Paste")
			(net "P5E_CPU0_P3_RX_BUF_DP<10>")
		)
		(pad "BK35" smd oval
			(at 2.649982 3.940048)
			(size 0.254 0.3302)
			(layers "F.Cu" "F.Mask" "F.Paste")
			(net "P5E_CPU0_P3_TX_C_DP<10>")
		)
		(pad "BL4" smd circle
			(at 2.402586 -2.817368)
			(size 0.381 0.381)
			(layers "F.Cu" "F.Mask" "F.Paste")
			(net "GND")
		)
		(pad "BL13" smd circle
			(at 2.402586 -0.79629)
			(size 0.3048 0.3048)
			(layers "F.Cu" "F.Mask" "F.Paste")
			(net "GND")
		)
		(pad "BL17" smd circle
			(at 2.402586 -0.296164)
			(size 0.3048 0.3048)
			(layers "F.Cu" "F.Mask" "F.Paste")
			(net "P0V9_CPU0_RT_2D")
		)
		(pad "BL20" smd circle
			(at 2.402586 0.203708)
			(size 0.3048 0.3048)
			(layers "F.Cu" "F.Mask" "F.Paste")
			(net "P0V9_CPU0_RT_2D")
		)
		(pad "BL22" smd circle
			(at 2.402586 0.703834)
			(size 0.3048 0.3048)
			(layers "F.Cu" "F.Mask" "F.Paste")
			(net "GND")
		)
		(pad "BL32" smd circle
			(at 2.402586 2.724912)
			(size 0.381 0.381)
			(layers "F.Cu" "F.Mask" "F.Paste")
			(net "GND")
		)
		(pad "BM2" smd circle
			(at 2.350008 -3.41884)
			(size 0.3048 0.3048)
			(layers "F.Cu" "F.Mask" "F.Paste")
			(net "GND")
		)
		(pad "BM34" smd circle
			(at 2.350008 3.420364)
			(size 0.3048 0.3048)
			(layers "F.Cu" "F.Mask" "F.Paste")
			(net "GND")
		)
		(pad "BN1" smd oval
			(at 2.050034 -3.938524)
			(size 0.254 0.3302)
			(layers "F.Cu" "F.Mask" "F.Paste")
			(net "GND")
		)
		(pad "BN35" smd oval
			(at 2.050034 3.940048)
			(size 0.254 0.3302)
			(layers "F.Cu" "F.Mask" "F.Paste")
			(net "GND")
		)
		(pad "BP7" smd circle
			(at 2.002536 -2.12471)
			(size 0.381 0.381)
			(layers "F.Cu" "F.Mask" "F.Paste")
			(net "P5E_CPU0_P3_TX_BUF_DP<9>")
		)
		(pad "BP26" smd circle
			(at 2.002536 1.339342)
			(size 0.381 0.381)
			(layers "F.Cu" "F.Mask" "F.Paste")
			(net "P5E_CPU0_P3_RX_DP<9>")
		)
		(pad "BR2" smd circle
			(at 1.75006 -3.41884)
			(size 0.3048 0.3048)
			(layers "F.Cu" "F.Mask" "F.Paste")
			(net "P5E_CPU0_P3_RX_BUF_DN<9>")
		)
		(pad "BR34" smd circle
			(at 1.75006 3.420364)
			(size 0.3048 0.3048)
			(layers "F.Cu" "F.Mask" "F.Paste")
			(net "P5E_CPU0_P3_TX_C_DN<9>")
		)
		(pad "BT10" smd circle
			(at 1.602486 -1.431798)
			(size 0.381 0.381)
			(layers "F.Cu" "F.Mask" "F.Paste")
			(net "P5E_CPU0_P3_TX_BUF_DN<9>")
		)
		(pad "BT29" smd circle
			(at 1.602486 2.032254)
			(size 0.381 0.381)
			(layers "F.Cu" "F.Mask" "F.Paste")
			(net "P5E_CPU0_P3_RX_DN<9>")
		)
		(pad "BU1" smd oval
			(at 1.450086 -3.938524)
			(size 0.254 0.3302)
			(layers "F.Cu" "F.Mask" "F.Paste")
			(net "P5E_CPU0_P3_RX_BUF_DP<9>")
		)
		(pad "BU35" smd oval
			(at 1.450086 3.940048)
			(size 0.254 0.3302)
			(layers "F.Cu" "F.Mask" "F.Paste")
			(net "P5E_CPU0_P3_TX_C_DP<9>")
		)
		(pad "BV4" smd circle
			(at 1.20269 -2.817368)
			(size 0.381 0.381)
			(layers "F.Cu" "F.Mask" "F.Paste")
			(net "GND")
		)
		(pad "BV13" smd circle
			(at 1.20269 -0.79629)
			(size 0.3048 0.3048)
			(layers "F.Cu" "F.Mask" "F.Paste")
			(net "GND")
		)
		(pad "BV17" smd circle
			(at 1.20269 -0.296164)
			(size 0.3048 0.3048)
			(layers "F.Cu" "F.Mask" "F.Paste")
			(net "P1V8_CPU0_RT3_1A_1D")
		)
		(pad "BV20" smd circle
			(at 1.20269 0.203708)
			(size 0.3048 0.3048)
			(layers "F.Cu" "F.Mask" "F.Paste")
			(net "P1V8_CPU0_RT3_1A")
		)
		(pad "BV22" smd circle
			(at 1.20269 0.703834)
			(size 0.3048 0.3048)
			(layers "F.Cu" "F.Mask" "F.Paste")
			(net "GND")
		)
	)
)
